FILE_TYPE = MULTI_PHYS_TABLE;

PART 'CONN6_HBC1031L200D8H'

{========================================================================================}
:VALUE                    | PART_TYPE | MATERIAL | PART_NUMBER    = STANDARD        | LIFECYCLE      | PART_NUMBER   | JEDEC_TYPE    | DESCRIPTION                             | MANUFTR | MANUF_PN           | RD_CMPLS_LVL | CMPLS_LVL | CLASS | DIP_SMD | FROM_PJ     | DATA                       | FP_ECN | EE_CHECK_LIST | CREATOR | CREATEDAY  | PSL | STATUS | ESD_CDM | ESD_HBM | ESD_MM | MSD | PIN_LENGTH_LONG_PIN | PIN_LENGTH_SHORT_PIN ;
{========================================================================================}
 'CONN6_HBC1031-L200D-8H' | 'THLF'    | 'IO'     | 'DFHD06MS263'(!) = ''               | ''               | 'DFHD06MS263' |'HEADER2X3XE'| 'CONN DIP HEADER 6P 2R MS(P2.54,H8.38)' | 'FOX'   | 'HBC1031-L200D-8H' | 'EP(V1)'     | 'EP(V1)'  | 'IO'  | 'DIP'   | 'S9T-DAVID' | 'FOX_HBC1031-L200D-8H.pdf' | ''     | ''            | ''      | '20210512' | ''  | ''     | ''      | ''      | ''     | ''  | '110 MILS'          | '110 MILS'          
 'CONN6_HBC1031-L200D-8H' | 'THLF'    | 'EMPTY'  | 'DFHD06MS263'(!) = ''               | ''               | 'DFHD06MS263' |'HEADER2X3XE'| 'CONN DIP HEADER 6P 2R MS(P2.54,H8.38)' | 'FOX'   | 'HBC1031-L200D-8H' | 'EP(V1)'     | 'EP(V1)'  | 'IO'  | 'DIP'   | 'S9T-DAVID' | 'FOX_HBC1031-L200D-8H.pdf' | ''     | ''            | ''      | '20210512' | ''  | ''     | ''      | ''      | ''     | ''  | '110 MILS'          | '110 MILS'          

END_PART

END.

